# TimeCard_V8_BOM.xlsx — TimeCard_V8_BOM (bom)
| Line # | DNP | Name | Description | Designator | Revision ID | Revision State | Revision Status | Quantity | Manufacturer 1 | Manufacturer Part Number 1 | Manufacturer Lifecycle 1 | Supplier 1 | Supplier Part Number 1 | Supplier Unit Price 1 | Supplier Subtotal 1 |
|  |  | 39-30-0040 | CONN HEADER R/A 4POS 4.2MM | J38 | CMP-2000-05600-2 | New From Design | Up to date | 1 | Molex | 39-30-0040 | Unknown | Digi-Key | WM21352-ND | 1.24 | 1.24 |
|  |  | 2049261103 | CONN RCPT USB2.0 MICRO B SMD R/A | J43 | CMP-04767-000001-1 | New From Design | Up to date | 1 | Molex | 2049261103 | Unknown | Digi-Key | WM22189CT-ND | 5.63 | 5.63 |
|  |  | A6H-2102 | SWITCH SLIDE DIP SPST 25MA 24V | SW1 | CMP-08827-000068-1 | New From Design | Up to date | 1 | Omron | A6H-2102 | Unknown | Digi-Key | Z5461-ND | 3.66 | 3.66 |
|  |  | AT24MAC402-STUM-T | IC EEPROM 2K I2C 1MHZ SOT23-5 | U7 | CMP-06313-000011-1 | New From Design | Up to date | 1 |  |  |  |  |  |  |  |
|  |  | BNO055 | IMU ACCEL/GYRO/MAG I2C 28LGA | U13 | CMP-2000-05075-4 | New From Design | Up to date | 1 |  |  |  |  |  |  |  |
|  |  | CC0402KRX7R9BB103 | CAP CER 10000PF 50V X7R 0402 | C86, C91 | CMP-2100-03592-2 | New From Design | Up to date | 2 | Yageo | CC0402KRX7R9BB103 | Unknown | Digi-Key | 311-1349-1-ND | 1.6E-2 | 0.16 |
|  |  | CC0402KRX7R9BB472 | CAP CER 4700PF 50V X7R 0402 | C8, C73 | CMP-03422-001290-1 | New From Design | Up to date | 2 | Yageo | CC0402KRX7R9BB472 | Unknown | Digi-Key | 311-1418-1-ND | 1.7999999999999999E-2 | 0.18 |
|  |  | CC0603KRX7R9BB104 | CAP CER 0.1UF 50V X7R 0603 | C3, C9, C68, C74 | CMP-2100-03601-2 | New From Design | Up to date | 4 | Yageo | CC0603KRX7R9BB104 | Unknown | Digi-Key | 311-1344-1-ND | 0.1 | 0.4 |
|  |  | CL05A475MO5NUNC | Cap Ceramic 4.7uF 16V X5R ±20% SMD 0402 +85°C Paper T/R | C90 | CMP-13271-001468-1 | New From Design | Up to date | 1 | Samsung | CL05A475MO5NUNC | Unknown | Digi-Key | 1276-6836-1-ND | 0.44 | 0.44 |
|  |  | EMK105BJ105KV-F | None | C4, C17, C69, C82 | CMP-14477-000104-2 | New From Design | Up to date | 4 | Taiyo Yuden | EMK105BJ105KV-F | Unknown | Digi-Key | 587-2477-1-ND | 0.1 | 0.4 |
|  |  | EMK105BJ105MV-F | None | C65 | CMP-14477-003537-2 | New From Design | Up to date | 1 | Taiyo Yuden | EMK105BJ105MV-F | Unknown | Digi-Key | 587-5514-1-ND | 0.1 | 0.1 |
|  |  | ERJ-2RKF1502X | RES SMD 15K OHM 1% 1/10W 0402 | R83 | CMP-2002-00694-4 | New From Design | Up to date | 1 | Panasonic | ERJ-2RKF1502X | Volume Production | Digi-Key | P15.0KLDKR-ND | 0.1 | 0.1 |
|  |  | FT234XD-R | IC USB SERIAL BASIC UART 12DFN | U20 | CMP-0248-00027-3 | New From Design | Up to date | 1 | FTDI | FT234XD-R | Unknown | Digi-Key | 768-1178-1-ND | 2.2599999999999998 | 2.2599999999999998 |
|  |  | GRM31CR71H475KA12L | Chip Multilayer Ceramic Capacitors for General Purpose, 1206, 4.7uF, X7R, 15%, 10%, 50V | C11, C12, C76, C77 | CMP-1037-04923-3 | New From Design | Up to date | 4 | Murata | GRM31CR71H475KA12L | Unknown | Digi-Key | 490-6521-1-ND | 0.4 | 1.6 |
|  |  | IHLP2525EZER2R2M01 | Commercial Inductors, High Saturation Series 2.2uH 10A 13.6mΩ 20% | L1, L2 | CMP-02424-000315-1 | New From Design | Up to date | 2 | Vishay Dale | IHLP2525EZER2R2M01 | Unknown | Digi-Key | 541-2586-1-ND | 2.2599999999999998 | 4.5199999999999996 |
|  |  | LTST-C191TBKT | LED BLUE CLEAR CHIP SMD | D3, D9, D10, D11 | CMP-22017-000008-1 | New From Design | Up to date | 4 | Vishay Lite-On | LTST-C191TBKT | Unknown | Digi-Key | 160-1647-1-ND | 0.33 | 1.32 |
|  |  | SD103AWS-7-F | DIODE SCHOTTKY 40V 350MA SOD323 | D21, D22 | CMP-12790-000048-1 | New From Design | Up to date | 2 | Diodes | SD103AWS-7-F | Unknown | Digi-Key | SD103AWS-FDICT-ND | 0.38 | 0.76 |
|  |  | SMDJ12A | TVS DIODE 12V 19.9V DO214AB | D23 | CMP-08607-000111-1 | New From Design | Up to date | 1 | Littelfuse | SMDJ12A | Unknown | Digi-Key | SMDJ12ACT-ND | 0.9 | 0.9 |
|  |  | SML-LX0603IW-TR | LED RED DIFFUSED SMD | D4, D20, D24, D25 | CMP-57192-000012-1 | New From Design | Up to date | 4 | Lumex | SML-LX0603IW-TR | Unknown | Digi-Key | 67-1548-1-ND | 0.33 | 1.32 |
|  |  | STPS5L60S | DIODE SCHOTTKY 60V 5A SMC | D12, D19 | CMP-12187-000009-2 | New From Design | Up to date | 2 | STMicroelectronics | STPS5L60S | Unknown | Digi-Key | 497-8487-1-ND | 0.93 | 1.86 |
|  |  | TMK212BBJ106KG-T | None | C34, C35, C41, C42, C55, C56, C58, C60 | CMP-14477-000079-2 | New From Design | Out of date | 8 | Taiyo Yuden | TMK212BBJ106KG-T | Unknown | Digi-Key | 587-2985-1-ND | 0.124 | 1.24 |
|  |  | TMUX1072RUTR | IC SWITCH SPDT DUAL 12UQFN | U21, U22, U23 | CMP-04892-000114-1 | New From Design | Up to date | 3 | Texas Instruments | TMUX1072RUTR | Unknown | Digi-Key | 296-50285-1-ND | 1.5 | 4.5 |
|  |  | BME280 | SENSOR PRESSURE HUMIDITY TEMP | U14 | CMP-2000-05073-3 | New From Design | Up to date | 1 |  |  |  |  |  |  |  |
|  |  | 0332-0-43-80-18-27-10-0 | Solder socket for pin headers | SKT1, SKT2, SKT3, SKT4, SKT5, SKT6, SKT7, SKT8, SKT9, SKT10 |  | Not managed |  | 10 |  |  |  |  |  |  |  |
|  |  | 155124M173200 | LED (Multiple) | D13, D14, D15, D16, D17, D18 |  | Not managed |  | 6 | Wurth Electronics | 155124M173200 | Unknown | Digi-Key | 732-11414-1-ND | 0.53 | 3.18 |
|  |  | BAT54SW | DIO, SCHOTTKY, BAT54S, DUAL SERIES, 30V, 200MA, SC-70 | D5, D6, D7, D8 |  | Not managed |  | 4 | Diodes | BAT54SWQ-7-F | Unknown | Digi-Key | BAT54SWQ-7-FDICT-ND | 0.34 | 1.36 |
|  |  | CAP_0402_0.1UF_50V | CAP, CER, 0.1UF, 50V, 10%, X7R, AEC-Q200, 0402 | C44, C45, C46, C47, C48, C49, C50, C51, C52, C53 |  | Not managed |  | 10 | TDK | CGA2B3X7R1H104K050BB | Unknown | Digi-Key | 445-6899-1-ND | 0.10299999999999999 | 1.03 |
|  |  | CAP_0805_10UF_25V | CAP, CER, 10.UF, 25V, 10%, X5R, 0805 | C1, C62 |  | Not managed |  | 2 | Taiyo Yuden | TMK212BBJ106KG-T | Unknown | Mouser | 963-TMK212BBJ106KG-T | 0.2 | 0.4 |
|  |  | CRCW080533R0FKEA | RES, 33 OHM, 1%, 1/8W, TF, 0805 | R18, R19, R20, R21 |  | Not managed |  | 4 | Vishay | CRCW080533R0FKEA | Unknown | Digi-Key | 541-33.0CCT-ND | 0.1 | 0.4 |
|  |  | ERJ-2GE0R00X | RES, 0. OHM, 1%, 1/16W, TF, AEC-Q200, 0402 | R23, R24 |  | Not managed |  | 2 | Panasonic | ERJ-2GE0R00X | Unknown | Digi-Key | P0.0JCT-ND | 0.1 | 0.2 |
|  |  | ERJ-3EKF4701V | RES, 4.7K, 1%, 1/10W, TF, 0603 | R22 |  | Not managed |  | 1 | Panasonic | ERJ-3EKF4701V | Unknown | Digi-Key | P4.70KHCT-ND | 0.1 | 0.1 |
|  |  | FUSE_0603_5.00A | FUSE SLOW 5.00A 32V M 0603 | F1 |  | Not managed |  | 1 | Bourns | SF-0603S500-2 | Unknown | Digi-Key | SF-0603S500-2CT-ND | 0.6 | 0.6 |
|  |  | GNSS Header 16-pin |  | J6, J13 |  | Not managed |  | 2 | Samtec | SQW-108-01-F-D-VS | Unknown | Digi-Key | SAM11878-ND | 3.61 | 7.22 |
|  |  | GNSS Standoff |  | J5, J7, J8, J9, J10, J11, J12, J14 |  | Not managed |  | 8 | Keystone Electronics | 24393 | Volume Production | Digi-Key | 36-24393-ND | 0.75 | 6 |
|  |  | IS32FL3207 |  | U6 |  | Not managed |  | 1 | ISSI | IS32FL3207-QWLA3-TR | Unknown | Digi-Key | 2521-IS32FL3207-QWLA3-TRCT-ND | 2.35 | 2.35 |
|  |  | M3 screw |  | J15, J16, J17, J18, J19, J20, J21, J22, J23, J24, J25, J26, J27, J28, J29, J30, J32, J33 |  | Not managed |  | 18 | APM Hexseal | RM3X6MM2701 | Volume Production | Digi-Key | 335-1156-ND | 0.45400000000000001 | 8.17 |
|  |  | MIC24052YJL-TR | No Description Available | U1, U18 |  | Not managed |  | 2 |  |  |  |  |  |  |  |
|  |  | NC7WV125K8X | Integrated Circuit | U8, U11, U12, U16 |  | Not managed |  | 4 | ON Semiconductor / Fairchild | NC7WV125K8X | Volume Production | Digi-Key | NC7WV125K8XCT-ND | 0.8 | 3.2 |
|  |  | SA53 Screw |  | J39, J40, J41, J42 |  | Not managed |  | 4 | B&F Fastener | PMSSS2560025PH | Volume Production | Digi-Key | H700-ND |  |  |
|  |  | SA53_Header |  | J31 |  | Not managed |  | 1 | Molex | 52991-0208 | Unknown | Digi-Key | WM24007CT-ND | 2.27 | 2.27 |
|  |  | Single FPGA Conn |  | J34, J35, J36, J37 |  | Not managed |  | 4 | Panasonic | AXK680347YG | Unknown | Digi-Key | 255-3246-1-ND | 3.13 | 12.52 |
|  |  | HTST-105-01-L-DV-A | CONN, HDR, 2X5, VERT, 0.1IN  SHROUDED, SMT, HTSH SERIES | U5 |  | Not managed |  | 1 | Samtec | HTST-105-01-L-DV-A | Unknown | Digi-Key | SAM8809-ND |  |  |
|  | DNP | EXT GPIO | Header, 6-Pin, Dual row | P3 |  | Not managed |  | 1 |  |  |  |  |  |  |  |
|  | DNP | MAC-SA5X | MOD, MAC, MAC-SA5X, ATOMIC CLOCK | U10 |  | Not managed |  | 1 |  |  |  |  |  |  |  |
|  | DNP | PCIex4 | PCIE x4 Edge Connector,OrCAD Symbol,NC | P2 |  | Not managed |  | 1 |  |  |  |  |  |  |  |
|  | DNP | RCB-F9T | MOD, GPS | U9 |  | Not managed |  | 1 | u-blox | RCB-F9T | Unknown | Digi-Key | 672-RCB-F9T-ND | 278.44 | 278.44 |
|  | DNP | RCB-F9T-1 | MOD, GPS | U15 |  | Not managed |  | 1 | u-blox | RCB-F9T | Unknown | Digi-Key | 672-RCB-F9T-ND | 278.44 | 278.44 |
|  |  | 1R21 1% 0402(1005) | 1R21 0.063W 1% 0402 (1005 Metric)  SMD | R4, R5, R69, R70 | CMP-1011-00180-1 | Released | Up to date | 4 | Vishay Dale | CRCW04021R21FKED | Unknown | Digi-Key | 541-1.21LLCT-ND | 0.1 | 0.4 |
|  |  | 901-143-6RFX | Coaxial connector, 50 Ohm, -65 to 165 degC, 5-Pin THD, RoHS, Bulk | AN1, AN2, AN3, AN4 | CMP-2000-05705-1 | Released | Up to date | 4 | Adam Equipment | RF2-49B-T-00-50-G-HDW | Unknown | Digi-Key | 2057-RF2-49B-T-00-50-G-HDW-ND | 3.08 | 12.32 |
|  |  | 04023C104KAT2A | General Purpose Ceramic Capacitor, 0402, 100nF, 10%, X7R, 15%, 25V | C6, C18, C71, C83, C89, C92, C93, C94, C95, C96 | CMP-2008-02519-2 | Released | Up to date | 10 | Kyocera AVX | 04023C104KAT2A | Unknown | Digi-Key | 478-7868-6-ND | 3.3000000000000002E-2 | 0.33 |
|  |  | 1909763-1 | Ultra Miniature Coaxial Connector Jack, 60 V, 50 Ohm, -40 to 90 degC, RoHS, Tape and Reel | J1, J2, J3, J4 | CMP-2000-07505-1 | Released | Out of date | 4 | TE Connectivity AMP | 1909763-1 | Unknown | Digi-Key | A118077CT-ND | 0.6 | 2.4 |
|  |  | 8240136 | TVS Diode WE-TVS-HS, VRWM=3.3V | D1, D2 | CMP-1486-00002-1 | Released | Up to date | 2 | Wurth Electronics | 8240136 | Unknown | Digi-Key | 732-4472-1-ND | 1.28 | 2.56 |
|  |  | BLM18KG601SN1D | Chip Ferrite Bead, 0603, 600Ω @ 100MHz, 0.15Ω, 25%, 1.3A | FB1 | CMP-0686-00581-3 | Released | Up to date | 1 | Murata | BLM18KG601SN1D | Unknown | Digi-Key | 490-5258-1-ND | 0.1 | 0.1 |
|  |  | C0603C105K3PACTU | CAP CER 1UF 25V X5R 0603 | C38 | CMP-2006-02216-3 | Released | Up to date | 1 | KEMET | C0603C105K3PACTU | Unknown | Digi-Key | 399-C0603C105K3PAC7867CT-ND | 0.18 | 0.18 |
|  |  | C0603X104K5RACAUTO |  | C2, C23, C24, C25, C26, C27, C28, C29, C30, C31, C36, C37, C40, C43, C54, C57, C59, C61, C63, C64 | CMP-2006-00003-1 | Released | Out of date | 20 | KEMET | C0603X104K5RACAUTO | Unknown | Digi-Key | 399-6912-1-ND | 0.13300000000000001 | 2.66 |
|  |  | C1005X5R1C225K050BC | Multilayer Ceramic Capacitors 2.2μF ±10% 16V X5R SMD 0402 | C5, C16, C70, C81 | CMP-2000-05998-2 | Released | Up to date | 4 | TDK | C1005X5R1C225K050BC | Unknown | Digi-Key | 445-9085-1-ND | 0.26 | 1.04 |
|  |  | C3216X5R1C476M160AB | Multilayer Ceramic Capacitors 47uF ±20% 16V X5R SMD 1206 | C13, C78 | CMP-2000-07442-2 | Released | Up to date | 2 | TDK | C3216X5R1C476M160AB | Unknown | Digi-Key | 445-6003-1-ND | 0.95 | 1.9 |
|  |  | CR0402-FX-7870GLF |  | R78 | CMP-2002-05402-1 | Released | Up to date | 1 | Bourns | CR0402-FX-7870GLF | Unknown |  |  |  |  |
|  |  | CRCW040227R0FKED |  | R13, R42, R43, R81, R84, R85, R86, R87, R90, R91, R92, R93 | CMP-2002-08434-1 | Released | Up to date | 12 | Vishay | CRCW040227R0FKED | Unknown |  |  |  |  |
|  |  | CRCW0603110RFKEA |  | R12 | CMP-2000-03854-1 | Released | Up to date | 1 | Vishay | CRCW0603110RFKEA | Unknown |  |  |  |  |
|  |  | CRCW12060000Z0EAHP |  | R45 | CMP-2003-04873-1 | Released | Up to date | 1 | Vishay Dale | CRCW12060000Z0EAHP | Unknown |  |  |  |  |
|  |  | DS90LV027AQMA | Automotive LVDS Dual Differential Driver, 8-pin Narrow SOIC | U3 | CMP-0058-01000-2 | Released | Up to date | 1 | TI National Semiconductor | DS90LV027AQMA | Unknown |  |  |  |  |
|  |  | DS90LV028AQMA | Automotive LVDS Dual Differential Line Receiver, 8-pin Narrow SOIC | U4 | CMP-0058-01010-2 | Released | Up to date | 1 | TI National Semiconductor | DS90LV028AQMA | Unknown |  |  |  |  |
|  |  | EMK107BBJ106MA-T | Multilayer Ceramic Capacitor 10uF 16V X5R 20% SMD 0603 T/R | C15, C20, C22, C80, C85 | CMP-2000-06226-4 | Released | Up to date | 5 | Taiyo Yuden | EMK107BBJ106MA-T | Unknown | Digi-Key | 587-3238-1-ND | 0.31 | 1.55 |
|  |  | ERJ2GE0R00X | Chip Resistor, 0 Ohm, 0.1 W, -55 to 155 degC, 0402 (1005 Metric), RoHS, Tape and Reel | R48, R49, R54, R62, R64, R65, R66, R79, R80 | CMP-2000-07451-1 | Released | Up to date | 9 | Panasonic | ERJ-2GE0R00X | Unknown | Digi-Key | P0.0JDKR-ND | 2.7E-2 | 0.27 |
|  |  | ERJ-2RKF2000X | RES SMD 200 OHM 1% 1/10W 0402 | R1, R77, R94, R95 | CMP-2002-00757-2 | Released | Up to date | 4 | Panasonic | ERJ-2RKF2000X | Unknown | Digi-Key | P200LCT-ND | 3.4000000000000002E-2 | 0.34 |
|  |  | ERJ-2RKF4701X | Chip Resistor, 4.7 KOhm, +/- 1%, 0.1 W, -55 to 155 degC, 0402 (1005 Metric), RoHS, Tape and Reel | R2, R3, R50, R51, R52, R53, R55, R57, R58, R67, R68, R108, R109 | CMP-2002-01154-4 | Released | Up to date | 13 | Panasonic | ERJ-2RKF4701X | Unknown | Digi-Key | P4.70KLCT-ND | 3.4000000000000002E-2 | 0.442 |
|  |  | ERJ-3EKF2000V |  | R35, R36, R38, R39 | CMP-2000-00316-1 | Released | Out of date | 4 | Panasonic | ERJ-3EKF2000V | Unknown | Digi-Key | P200HCT-ND | 0.1 | 0.4 |
|  |  | ERJ-3EKF4701V | Precision Thick Film Chip Resistor, 4.7 KOhm, +/- 1%, -55 to 155 degC, 0603 (1608 Metric), RoHS, Tape and Reel | R14, R15, R16, R17, R26, R27, R29, R30, R31, R32, R41 | CMP-1012-00586-3 | Released | Up to date | 11 | Yageo | RC0603FR-074K7L | Unknown | Digi-Key | 311-4.70KHRDKR-ND | 1.9E-2 | 0.20899999999999999 |
|  |  | GRM1555C1H470JA01D |  | C87, C88 | CMP-2008-04368-1 | Released | Up to date | 2 | Murata | GRM1555C1H470JA01D | Unknown | Digi-Key | 490-5942-1-ND | 1.7000000000000001E-2 | 0.17 |
|  |  | INA219BIDR | IC MONITOR PWR/CURR BIDIR 8-SOIC | U2, U17, U19 | CMP-0704-00005-3 | Released | Up to date | 3 | Texas Instruments | INA219BIDR | Unknown | Digi-Key | 296-27899-1-ND | 2.97 | 8.91 |
|  |  | 0402YC104KAT2A |  | C19, C21, C32, C33, C66, C67, C84 | CMP-2008-00031-1 | Released | Up to date | 7 | Kyocera AVX | 0402YC104KAT2A | Unknown | Digi-Key | 478-7888-2-ND | 0.1 | 0.70000000000000007 |
|  |  | RC0402FR-072K49L |  | R61, R76 | CMP-2002-07571-1 | Released | Up to date | 2 | Yageo | RC0402FR-072K49L | Unknown | Digi-Key | 311-2.49KLRCT-ND | 1.4E-2 | 0.14000000000000001 |
|  |  | RC0402FR-072R21L |  | R6, R59, R71, R74 | CMP-1011-00208-2 | Released | Up to date | 4 | Yageo | RC0402FR-072R21L | Unknown | Digi-Key | 13-RC0402FR-072R21LCT-ND | 2.1999999999999999E-2 | 0.22 |
|  |  | RC0402FR-0710KL |  | R82, R88, R89 | CMP-2002-07353-1 | Released | Up to date | 3 | Yageo | RC0402FR-0710KL | Volume Production |  |  |  |  |
|  |  | RC0402FR-0719K6L |  | R60, R75 | CMP-2002-07443-1 | Released | Up to date | 2 | Yageo | RC0402FR-0719K6L | Unknown | Digi-Key | YAG3026CT-ND | 1.4E-2 | 0.14000000000000001 |
|  |  | RC0402FR-0749R9L |  | R96, R97, R98, R99 | CMP-2002-07709-1 | Released | Up to date | 4 | Yageo | RC0402FR-0749R9L | Unknown | Digi-Key | 311-49.9LRCT-ND | 1.4E-2 | 0.14000000000000001 |
|  |  | RC0402FR-07470RL |  | R63 | CMP-2002-07697-1 | Released | Up to date | 1 | Yageo | RC0402FR-07470RL | Volume Production |  |  |  |  |
|  |  | RC0603FR-074K7L | Chip Resistor, 4.7 KOhm, +/- 1%, 0.1 W, -55 to 155 degC, 0603 (1608 Metric), RoHS, Tape and Reel | R10, R11 | CMP-2000-06942-1 | Released | Up to date | 2 | Yageo | RC0603FR-074K7L | Unknown | Digi-Key | 311-4.70KHRDKR-ND | 1.9E-2 | 0.19 |
|  |  | RC0603FR-0749R9L | General Purpose Chip Resistor, 49.9 Ohm, +/- 1%, -55 to 155 degC, 0603 (1608 Metric), RoHS, Tape and Reel | R25, R28, R33, R34 | CMP-1659-00036-1 | Released | Up to date | 4 | Yageo | RC0603FR-0749R9L | Unknown | Digi-Key | 311-49.9HRCT-ND | 1.9E-2 | 0.19 |
|  |  | RK73H1ETTP1R21F |  | R9, R73 | CMP-2002-04265-1 | Released | Up to date | 2 | KOA Speer | RK73H1ETTP1R21F | Unknown |  |  |  |  |
|  |  | RMCF0603FT10K0 | Chip Resistor, 10 KOhm, +/- 1%, 0.1 W, -55 to 155 degC, 0603 (1608 Metric), RoHS, Tape and Reel | R37 | CMP-2000-06990-1 | Released | Out of date | 1 | Stackpole Electronics | RMCF0603FT10K0 | Unknown | Digi-Key | RMCF0603FT10K0CT-ND | 0.1 | 0.1 |
|  |  | T495D107K016ATE125 | CAP TANT 100UF 10% 16V 2917 | C10, C14, C75, C79 | CMP-2000-07207-2 | Released | Up to date | 4 | KEMET | T495D107K016ATE125 | Unknown | Digi-Key | 399-8499-1-ND | 2 | 8 |
|  |  | TSW-105-05-L-S | 0.025" SQ Post Header, Through-hole, Vertical, -55 to 125 degC, 2.54 mm Pitch, 5-Pin, Male, RoHS | P1 | CMP-1024-00366-1 | Released | Up to date | 1 | Samtec | TSW-105-05-L-S | Unknown |  |  |  |  |
|  |  | WSL12062L000FEA18 |  | R7, R8, R72 | CMP-2003-04334-1 | Released | Up to date | 3 | Vishay Dale | WSL12062L000FEA18 | Unknown | Digi-Key | 541-9996-1-ND | 1.65 | 4.95 |
